(kicad_pcb
	(version 20241229)
	(generator "pcbnew")
	(generator_version "9.0")
	(general
		(thickness 1.6)
		(legacy_teardrops no)
	)
	(paper "A4")
	(title_block
		(title "OCuLink to PCIe adapter")
		(date "2025-06-18")
		(rev "1.0.0")
		(company "Antmicro Ltd")
		(comment 1 "www.antmicro.com")
		(comment 9 "footprints 86-90 of 159")
	)
	(layers
		(0 "F.Cu" signal)
		(4 "In1.Cu" signal)
		(6 "In2.Cu" signal)
		(2 "B.Cu" signal)
		(9 "F.Adhes" user "F.Adhesive")
		(11 "B.Adhes" user "B.Adhesive")
		(13 "F.Paste" user)
		(15 "B.Paste" user)
		(5 "F.SilkS" user "F.Silkscreen")
		(7 "B.SilkS" user "B.Silkscreen")
		(1 "F.Mask" user)
		(3 "B.Mask" user)
		(17 "Dwgs.User" user "User.Drawings")
		(19 "Cmts.User" user "User.Comments")
		(21 "Eco1.User" user "User.Eco1")
		(23 "Eco2.User" user "User.Eco2")
		(25 "Edge.Cuts" user)
		(27 "Margin" user)
		(31 "F.CrtYd" user "F.Courtyard")
		(29 "B.CrtYd" user "B.Courtyard")
		(35 "F.Fab" user)
		(33 "B.Fab" user)
	)
	(footprint "antmicro-footprints:R_0402_1005Metric"
		(layer "F.Cu")
		(at 127.332999 152.076998 -90)
		(descr "Resistor SMD 0402")
		(tags "resistor SMD 0402")
		(property "Reference" "R13"
			(at 0.923002 0.332999 270)
			(layer "F.SilkS")
			(effects
				(font
					(size 0.7 0.7)
					(thickness 0.15)
				)
				(justify right top)
			)
		)
		(property "Value" "R_0R_0402"
			(at -1.011843 1.772046 90)
			(layer "F.Fab")
			(effects
				(font
					(size 0.7 0.7)
					(thickness 0.15)
				)
				(justify right top)
			)
		)
		(property "Datasheet" "https://industrial.panasonic.com/cdbs/www-data/pdf/RDA0000/AOA0000C301.pdf"
			(at 0 0 90)
			(layer "F.Fab")
			(hide yes)
			(effects
				(font
					(size 1.27 1.27)
					(thickness 0.15)
				)
			)
		)
		(property "Description" "SMD Chip Resistor, Jumper, 0 ohm, 100 mW, 0402 [1005 Metric], Thick Film, General Purpose"
			(at 0 0 90)
			(layer "F.Fab")
			(hide yes)
			(effects
				(font
					(size 1.27 1.27)
					(thickness 0.15)
				)
			)
		)
		(property "MPN" "ERJ2GE0R00X"
			(at 0 0 270)
			(unlocked yes)
			(layer "F.Fab")
			(hide yes)
			(effects
				(font
					(size 1 1)
					(thickness 0.15)
				)
			)
		)
		(property "Manufacturer" "Panasonic"
			(at 0 0 270)
			(unlocked yes)
			(layer "F.Fab")
			(hide yes)
			(effects
				(font
					(size 1 1)
					(thickness 0.15)
				)
			)
		)
		(property "License" "Apache-2.0"
			(at 0 0 270)
			(unlocked yes)
			(layer "F.Fab")
			(hide yes)
			(effects
				(font
					(size 1 1)
					(thickness 0.15)
				)
			)
		)
		(property "Author" "Antmicro"
			(at 0 0 270)
			(unlocked yes)
			(layer "F.Fab")
			(hide yes)
			(effects
				(font
					(size 1 1)
					(thickness 0.15)
				)
			)
		)
		(property "Val" "0R"
			(at 0 0 270)
			(unlocked yes)
			(layer "F.Fab")
			(hide yes)
			(effects
				(font
					(size 1 1)
					(thickness 0.15)
				)
			)
		)
		(property "Tolerance" ""
			(at 0 0 270)
			(unlocked yes)
			(layer "F.Fab")
			(hide yes)
			(effects
				(font
					(size 1 1)
					(thickness 0.15)
				)
			)
		)
		(property "Current" "1A"
			(at 0 0 270)
			(unlocked yes)
			(layer "F.Fab")
			(hide yes)
			(effects
				(font
					(size 1 1)
					(thickness 0.15)
				)
			)
		)
		(sheetname "/Power/")
		(sheetfile "power.kicad_sch")
		(attr smd)
		(fp_rect
			(start -0.925 -0.47)
			(end 0.925 0.47)
			(stroke
				(width 0.05)
				(type default)
			)
			(fill no)
			(layer "F.CrtYd")
		)
		(fp_rect
			(start -0.5 -0.25)
			(end 0.5 0.25)
			(stroke
				(width 0.15)
				(type solid)
			)
			(fill no)
			(layer "F.Fab")
		)
		(fp_text user "License: Apache-2.0"
			(at -0.949999 5.169 90)
			(layer "F.Fab")
			(effects
				(font
					(size 0.7 0.7)
					(thickness 0.15)
				)
				(justify right top)
			)
		)
		(fp_text user "${REFERENCE}"
			(at 0 0 90)
			(layer "F.Fab")
			(effects
				(font
					(size 0.7 0.7)
					(thickness 0.15)
				)
				(justify right top)
			)
		)
		(fp_text user "Author: Antmicro"
			(at -0.95 4.169 90)
			(layer "F.Fab")
			(effects
				(font
					(size 0.7 0.7)
					(thickness 0.15)
				)
				(justify right top)
			)
		)
		(pad "1" smd roundrect
			(at -0.48 0 270)
			(size 0.59 0.64)
			(layers "F.Cu" "F.Mask" "F.Paste")
			(roundrect_rratio 0.25)
			(net 177 "Net-(U6-2Y)")
			(pintype "passive")
		)
		(pad "2" smd roundrect
			(at 0.48 0 270)
			(size 0.59 0.64)
			(layers "F.Cu" "F.Mask" "F.Paste")
			(roundrect_rratio 0.25)
			(net 172 "/Power/~{PERST}")
			(pintype "passive")
		)
	)
	(footprint "antmicro-footprints:R_0402_1005Metric"
		(layer "F.Cu")
		(at 146 63 180)
		(descr "Resistor SMD 0402")
		(tags "resistor SMD 0402")
		(property "Reference" "R57"
			(at -1.2 1.4 0)
			(layer "F.SilkS")
			(effects
				(font
					(size 0.7 0.7)
					(thickness 0.15)
				)
				(justify right top)
			)
		)
		(property "Value" "R_50R_0402"
			(at -1.011843 1.772046 0)
			(layer "F.Fab")
			(effects
				(font
					(size 0.7 0.7)
					(thickness 0.15)
				)
				(justify right top)
			)
		)
		(property "Datasheet" "https://www.bourns.com/docs/product-datasheets/cr.pdf"
			(at 0 0 0)
			(layer "F.Fab")
			(hide yes)
			(effects
				(font
					(size 1.27 1.27)
					(thickness 0.15)
				)
			)
		)
		(property "Description" "SMD Chip Resistor"
			(at 0 0 0)
			(layer "F.Fab")
			(hide yes)
			(effects
				(font
					(size 1.27 1.27)
					(thickness 0.15)
				)
			)
		)
		(property "MPN" "CR0402-FX-50R0GLF"
			(at 0 0 180)
			(unlocked yes)
			(layer "F.Fab")
			(hide yes)
			(effects
				(font
					(size 1 1)
					(thickness 0.15)
				)
			)
		)
		(property "Manufacturer" "Bourns"
			(at 0 0 180)
			(unlocked yes)
			(layer "F.Fab")
			(hide yes)
			(effects
				(font
					(size 1 1)
					(thickness 0.15)
				)
			)
		)
		(property "License" "Apache-2.0"
			(at 0 0 180)
			(unlocked yes)
			(layer "F.Fab")
			(hide yes)
			(effects
				(font
					(size 1 1)
					(thickness 0.15)
				)
			)
		)
		(property "Author" "Antmicro"
			(at 0 0 180)
			(unlocked yes)
			(layer "F.Fab")
			(hide yes)
			(effects
				(font
					(size 1 1)
					(thickness 0.15)
				)
			)
		)
		(property "Val" "50R"
			(at 0 0 180)
			(unlocked yes)
			(layer "F.Fab")
			(hide yes)
			(effects
				(font
					(size 1 1)
					(thickness 0.15)
				)
			)
		)
		(property "Tolerance" "1%"
			(at 0 0 180)
			(unlocked yes)
			(layer "F.Fab")
			(hide yes)
			(effects
				(font
					(size 1 1)
					(thickness 0.15)
				)
			)
		)
		(sheetname "/PCIe-clock-generator/")
		(sheetfile "pcie-clock-generator.kicad_sch")
		(attr smd exclude_from_bom dnp)
		(fp_poly
			(pts
				(xy -0.925 -0.47) (xy 0.925 -0.47) (xy 0.925 0.47) (xy -0.925 0.47)
			)
			(stroke
				(width 0.05)
				(type default)
			)
			(fill no)
			(layer "F.CrtYd")
		)
		(fp_poly
			(pts
				(xy -0.5 -0.25) (xy 0.5 -0.25) (xy 0.5 0.25) (xy -0.5 0.25)
			)
			(stroke
				(width 0.15)
				(type solid)
			)
			(fill no)
			(layer "F.Fab")
		)
		(fp_text user "License: Apache-2.0"
			(at -0.949999 5.169 0)
			(layer "F.Fab")
			(effects
				(font
					(size 0.7 0.7)
					(thickness 0.15)
				)
				(justify right top)
			)
		)
		(fp_text user "Author: Antmicro"
			(at -0.95 4.169 0)
			(layer "F.Fab")
			(effects
				(font
					(size 0.7 0.7)
					(thickness 0.15)
				)
				(justify right top)
			)
		)
		(fp_text user "${REFERENCE}"
			(at -0.95 3.168 0)
			(layer "F.Fab")
			(effects
				(font
					(size 0.7 0.7)
					(thickness 0.15)
				)
				(justify right top)
			)
		)
		(pad "1" smd roundrect
			(at -0.48 0 180)
			(size 0.59 0.64)
			(layers "F.Cu" "F.Mask" "F.Paste")
			(roundrect_rratio 0.25)
			(net 66 "GND")
			(pintype "passive")
		)
		(pad "2" smd roundrect
			(at 0.48 0 180)
			(size 0.59 0.64)
			(layers "F.Cu" "F.Mask" "F.Paste")
			(roundrect_rratio 0.25)
			(net 179 "/PCIe-clock-generator/PCIe_{REF1}_R.CK-")
			(pintype "passive")
		)
	)
	(footprint "antmicro-footprints:R_0402_1005Metric"
		(layer "F.Cu")
		(at 125.332999 152.076998 90)
		(descr "Resistor SMD 0402")
		(tags "resistor SMD 0402")
		(property "Reference" "R8"
			(at -2.523002 0.467001 270)
			(layer "F.SilkS")
			(effects
				(font
					(size 0.7 0.7)
					(thickness 0.15)
				)
				(justify left bottom)
			)
		)
		(property "Value" "R_100k_0402"
			(at -1.011843 1.772046 90)
			(layer "F.Fab")
			(effects
				(font
					(size 0.7 0.7)
					(thickness 0.15)
				)
				(justify left bottom)
			)
		)
		(property "Datasheet" "https://www.bourns.com/docs/product-datasheets/cr.pdf"
			(at 0 0 90)
			(layer "F.Fab")
			(hide yes)
			(effects
				(font
					(size 1.27 1.27)
					(thickness 0.15)
				)
			)
		)
		(property "Description" "SMD Chip Resistor, 100 kohm, ± 1%, 62.5 mW, 0402 [1005 Metric], Thick Film, General Purpose"
			(at 0 0 90)
			(layer "F.Fab")
			(hide yes)
			(effects
				(font
					(size 1.27 1.27)
					(thickness 0.15)
				)
			)
		)
		(property "MPN" "CR0402-FX-1003GLF"
			(at 0 0 90)
			(unlocked yes)
			(layer "F.Fab")
			(hide yes)
			(effects
				(font
					(size 1 1)
					(thickness 0.15)
				)
			)
		)
		(property "Manufacturer" "Bourns"
			(at 0 0 90)
			(unlocked yes)
			(layer "F.Fab")
			(hide yes)
			(effects
				(font
					(size 1 1)
					(thickness 0.15)
				)
			)
		)
		(property "License" "Apache-2.0"
			(at 0 0 90)
			(unlocked yes)
			(layer "F.Fab")
			(hide yes)
			(effects
				(font
					(size 1 1)
					(thickness 0.15)
				)
			)
		)
		(property "Author" "Antmicro"
			(at 0 0 90)
			(unlocked yes)
			(layer "F.Fab")
			(hide yes)
			(effects
				(font
					(size 1 1)
					(thickness 0.15)
				)
			)
		)
		(property "Val" "100k"
			(at 0 0 90)
			(unlocked yes)
			(layer "F.Fab")
			(hide yes)
			(effects
				(font
					(size 1 1)
					(thickness 0.15)
				)
			)
		)
		(property "Tolerance" "1%"
			(at 0 0 90)
			(unlocked yes)
			(layer "F.Fab")
			(hide yes)
			(effects
				(font
					(size 1 1)
					(thickness 0.15)
				)
			)
		)
		(sheetname "/Power/")
		(sheetfile "power.kicad_sch")
		(attr smd)
		(fp_rect
			(start -0.925 -0.47)
			(end 0.925 0.47)
			(stroke
				(width 0.05)
				(type default)
			)
			(fill no)
			(layer "F.CrtYd")
		)
		(fp_rect
			(start -0.5 -0.25)
			(end 0.5 0.25)
			(stroke
				(width 0.15)
				(type solid)
			)
			(fill no)
			(layer "F.Fab")
		)
		(fp_text user "${REFERENCE}"
			(at 0 0 90)
			(layer "F.Fab")
			(effects
				(font
					(size 0.7 0.7)
					(thickness 0.15)
				)
				(justify left bottom)
			)
		)
		(fp_text user "License: Apache-2.0"
			(at -0.949999 5.169 90)
			(layer "F.Fab")
			(effects
				(font
					(size 0.7 0.7)
					(thickness 0.15)
				)
				(justify left bottom)
			)
		)
		(fp_text user "Author: Antmicro"
			(at -0.95 4.169 90)
			(layer "F.Fab")
			(effects
				(font
					(size 0.7 0.7)
					(thickness 0.15)
				)
				(justify left bottom)
			)
		)
		(pad "1" smd roundrect
			(at -0.48 0 90)
			(size 0.59 0.64)
			(layers "F.Cu" "F.Mask" "F.Paste")
			(roundrect_rratio 0.25)
			(net 66 "GND")
			(pintype "passive")
		)
		(pad "2" smd roundrect
			(at 0.48 0 90)
			(size 0.59 0.64)
			(layers "F.Cu" "F.Mask" "F.Paste")
			(roundrect_rratio 0.25)
			(net 185 "/Power/~{PERST_CONN}")
			(pintype "passive")
		)
	)
	(footprint "antmicro-footprints:C_0402_1005Metric"
		(layer "F.Cu")
		(at 140.1 60)
		(descr "Capacitor SMD 0402")
		(tags "capacitor SMD 0402")
		(property "Reference" "C42"
			(at -1 -0.699 0)
			(layer "F.SilkS")
			(effects
				(font
					(size 0.7 0.7)
					(thickness 0.15)
				)
				(justify left bottom)
			)
		)
		(property "Value" "C_100n_0402"
			(at -1.022927 2.155213 0)
			(layer "F.Fab")
			(effects
				(font
					(size 0.7 0.7)
					(thickness 0.15)
				)
				(justify left bottom)
			)
		)
		(property "Datasheet" "https://www.murata.com/products/productdetail?partno=GRM155R61H104KE14%23"
			(at 0 0 0)
			(layer "F.Fab")
			(hide yes)
			(effects
				(font
					(size 1.27 1.27)
					(thickness 0.15)
				)
			)
		)
		(property "Description" "SMD Multilayer Ceramic Capacitor, 0.1 µF, 50 V, 0402 [1005 Metric], ± 10%, X5R, GRM Series"
			(at 0 0 0)
			(layer "F.Fab")
			(hide yes)
			(effects
				(font
					(size 1.27 1.27)
					(thickness 0.15)
				)
			)
		)
		(property "MPN" "GRM155R61H104KE14D"
			(at 0 0 0)
			(unlocked yes)
			(layer "F.Fab")
			(hide yes)
			(effects
				(font
					(size 1 1)
					(thickness 0.15)
				)
			)
		)
		(property "Manufacturer" "Murata"
			(at 0 0 0)
			(unlocked yes)
			(layer "F.Fab")
			(hide yes)
			(effects
				(font
					(size 1 1)
					(thickness 0.15)
				)
			)
		)
		(property "License" "Apache-2.0"
			(at 0 0 0)
			(unlocked yes)
			(layer "F.Fab")
			(hide yes)
			(effects
				(font
					(size 1 1)
					(thickness 0.15)
				)
			)
		)
		(property "Author" "Antmicro"
			(at 0 0 0)
			(unlocked yes)
			(layer "F.Fab")
			(hide yes)
			(effects
				(font
					(size 1 1)
					(thickness 0.15)
				)
			)
		)
		(property "Val" "100n"
			(at 0 0 0)
			(unlocked yes)
			(layer "F.Fab")
			(hide yes)
			(effects
				(font
					(size 1 1)
					(thickness 0.15)
				)
			)
		)
		(property "Voltage" "50V"
			(at 0 0 0)
			(unlocked yes)
			(layer "F.Fab")
			(hide yes)
			(effects
				(font
					(size 1 1)
					(thickness 0.15)
				)
			)
		)
		(property "Dielectric" "X5R"
			(at 0 0 0)
			(unlocked yes)
			(layer "F.Fab")
			(hide yes)
			(effects
				(font
					(size 1 1)
					(thickness 0.15)
				)
			)
		)
		(sheetname "/PCIe-clock-generator/")
		(sheetfile "pcie-clock-generator.kicad_sch")
		(attr smd exclude_from_bom dnp)
		(fp_rect
			(start -0.925 -0.47)
			(end 0.925 0.47)
			(stroke
				(width 0.05)
				(type default)
			)
			(fill no)
			(layer "F.CrtYd")
		)
		(fp_line
			(start -0.494 -0.25)
			(end 0.504 -0.25)
			(stroke
				(width 0.15)
				(type solid)
			)
			(layer "F.Fab")
		)
		(fp_line
			(start -0.494 0.248)
			(end -0.494 -0.25)
			(stroke
				(width 0.15)
				(type solid)
			)
			(layer "F.Fab")
		)
		(fp_line
			(start 0.504 -0.25)
			(end 0.504 0.248)
			(stroke
				(width 0.15)
				(type solid)
			)
			(layer "F.Fab")
		)
		(fp_line
			(start 0.504 0.248)
			(end -0.494 0.248)
			(stroke
				(width 0.15)
				(type solid)
			)
			(layer "F.Fab")
		)
		(fp_text user "License: Apache-2.0"
			(at -0.939 5.799 0)
			(layer "F.Fab")
			(effects
				(font
					(size 0.7 0.7)
					(thickness 0.15)
				)
				(justify left bottom)
			)
		)
		(fp_text user "${REFERENCE}"
			(at -0.939 4.599 0)
			(layer "F.Fab")
			(effects
				(font
					(size 0.7 0.7)
					(thickness 0.15)
				)
				(justify left bottom)
			)
		)
		(fp_text user "Author: Antmicro"
			(at -0.939 3.399 0)
			(layer "F.Fab")
			(effects
				(font
					(size 0.7 0.7)
					(thickness 0.15)
				)
				(justify left bottom)
			)
		)
		(pad "1" smd roundrect
			(at -0.48 0)
			(size 0.59 0.64)
			(layers "F.Cu" "F.Mask" "F.Paste")
			(roundrect_rratio 0.25)
			(net 66 "GND")
			(pintype "passive")
		)
		(pad "2" smd roundrect
			(at 0.48 0)
			(size 0.59 0.64)
			(layers "F.Cu" "F.Mask" "F.Paste")
			(roundrect_rratio 0.25)
			(net 134 "+3V3")
			(pintype "passive")
		)
	)
	(footprint "antmicro-footprints:C_0402_1005Metric"
		(layer "F.Cu")
		(at 146.561999 55.001)
		(descr "Capacitor SMD 0402")
		(tags "capacitor SMD 0402")
		(property "Reference" "C11"
			(at -3.161999 2.999 180)
			(layer "F.SilkS")
			(effects
				(font
					(size 0.7 0.7)
					(thickness 0.15)
				)
				(justify left bottom)
			)
		)
		(property "Value" "C_1u_25V_0402"
			(at -1.022927 2.155213 0)
			(layer "F.Fab")
			(effects
				(font
					(size 0.7 0.7)
					(thickness 0.15)
				)
				(justify left bottom)
			)
		)
		(property "Datasheet" "https://www.murata.com/products/productdetail?partno=GRM155R61E105KE11%23"
			(at 0 0 0)
			(layer "F.Fab")
			(hide yes)
			(effects
				(font
					(size 1.27 1.27)
					(thickness 0.15)
				)
			)
		)
		(property "Description" "SMD Multilayer Ceramic Capacitor, 1 µF, 25 V, 0402 [1005 Metric], ± 10%, X5R, GRM Series"
			(at 0 0 0)
			(layer "F.Fab")
			(hide yes)
			(effects
				(font
					(size 1.27 1.27)
					(thickness 0.15)
				)
			)
		)
		(property "MPN" "GRM155R61E105KE11J"
			(at 0 0 0)
			(unlocked yes)
			(layer "F.Fab")
			(hide yes)
			(effects
				(font
					(size 1 1)
					(thickness 0.15)
				)
			)
		)
		(property "Val" "1u"
			(at 0 0 0)
			(unlocked yes)
			(layer "F.Fab")
			(hide yes)
			(effects
				(font
					(size 1 1)
					(thickness 0.15)
				)
			)
		)
		(property "Voltage" "25V"
			(at 0 0 0)
			(unlocked yes)
			(layer "F.Fab")
			(hide yes)
			(effects
				(font
					(size 1 1)
					(thickness 0.15)
				)
			)
		)
		(property "Dielectric" "X5R"
			(at 0 0 0)
			(unlocked yes)
			(layer "F.Fab")
			(hide yes)
			(effects
				(font
					(size 1 1)
					(thickness 0.15)
				)
			)
		)
		(property "Manufacturer" "Murata"
			(at 0 0 0)
			(unlocked yes)
			(layer "F.Fab")
			(hide yes)
			(effects
				(font
					(size 1 1)
					(thickness 0.15)
				)
			)
		)
		(property "License" "Apache-2.0"
			(at 0 0 0)
			(unlocked yes)
			(layer "F.Fab")
			(hide yes)
			(effects
				(font
					(size 1 1)
					(thickness 0.15)
				)
			)
		)
		(property "Author" "Antmicro"
			(at 0 0 0)
			(unlocked yes)
			(layer "F.Fab")
			(hide yes)
			(effects
				(font
					(size 1 1)
					(thickness 0.15)
				)
			)
		)
		(sheetname "/USB-PD/")
		(sheetfile "usb-pd.kicad_sch")
		(attr smd)
		(fp_rect
			(start -0.925 -0.47)
			(end 0.925 0.47)
			(stroke
				(width 0.05)
				(type default)
			)
			(fill no)
			(layer "F.CrtYd")
		)
		(fp_line
			(start -0.494 -0.25)
			(end 0.504 -0.25)
			(stroke
				(width 0.15)
				(type solid)
			)
			(layer "F.Fab")
		)
		(fp_line
			(start -0.494 0.248)
			(end -0.494 -0.25)
			(stroke
				(width 0.15)
				(type solid)
			)
			(layer "F.Fab")
		)
		(fp_line
			(start 0.504 -0.25)
			(end 0.504 0.248)
			(stroke
				(width 0.15)
				(type solid)
			)
			(layer "F.Fab")
		)
		(fp_line
			(start 0.504 0.248)
			(end -0.494 0.248)
			(stroke
				(width 0.15)
				(type solid)
			)
			(layer "F.Fab")
		)
		(fp_text user "License: Apache-2.0"
			(at -0.939 5.799 0)
			(layer "F.Fab")
			(effects
				(font
					(size 0.7 0.7)
					(thickness 0.15)
				)
				(justify left bottom)
			)
		)
		(fp_text user "Author: Antmicro"
			(at -0.939 3.399 0)
			(layer "F.Fab")
			(effects
				(font
					(size 0.7 0.7)
					(thickness 0.15)
				)
				(justify left bottom)
			)
		)
		(fp_text user "${REFERENCE}"
			(at 0 0 0)
			(layer "F.Fab")
			(effects
				(font
					(size 0.7 0.7)
					(thickness 0.15)
				)
				(justify left bottom)
			)
		)
		(pad "1" smd roundrect
			(at -0.48 0)
			(size 0.59 0.64)
			(layers "F.Cu" "F.Mask" "F.Paste")
			(roundrect_rratio 0.25)
			(net 66 "GND")
			(pintype "passive")
		)
		(pad "2" smd roundrect
			(at 0.48 0)
			(size 0.59 0.64)
			(layers "F.Cu" "F.Mask" "F.Paste")
			(roundrect_rratio 0.25)
			(net 114 "/USB-PD/VCCD_1V8")
			(pintype "passive")
		)
	)
)
